# T6G (Grand Teton) — schematic netlist excerpt (pin names and nets, part order shuffled) for the footprints in the layout excerpt that follows; sources: Cadence DE-HDL packaged netlist, KiCad conversion of 04192023_DAF0TMB3IC0_F0TG_MB_C_brd_V02_OCP.brd

R1215  Q_RES  1K 1% CHIP  pkg 0201LF  page 186 : A = GND ; B = RT_ROM_MUX1_OE_N
C1920  Q_CAP  22UF 6.3V 20% X6S  pkg C0603  page 144 : A = P3V3_M2_0 ; B = GND
PR278  Q_RES  5.6 1% CHIP  pkg 0402LF  page 222 : A = SW_PVDDIO_P1_BOOT2 ; B = SW_PVDDIO_P1_BOOT2_R

(kicad_pcb
	(version 20260206)
	(generator "pcbnew")
	(generator_version "10.0")
	(general
		(thickness 1.6)
		(legacy_teardrops no)
	)
	(paper "A4")
	(title_block
		(title "04192023_DAF0TMB3IC0_F0TG_MB_C_brd_V02_OCP.brd")
		(comment 1 "Grand Teton / footprints 3681-3683 of 8354")
	)
	(layers
		(0 "F.Cu" signal "TOP")
		(4 "In1.Cu" signal "GND")
		(6 "In2.Cu" signal "IN1")
		(8 "In3.Cu" signal "GND1")
		(10 "In4.Cu" signal "IN2")
		(12 "In5.Cu" signal "GND2")
		(14 "In6.Cu" signal "IN3")
		(16 "In7.Cu" signal "GND3")
		(18 "In8.Cu" signal "VCC")
		(20 "In9.Cu" signal "VCC1")
		(22 "In10.Cu" signal "GND4")
		(24 "In11.Cu" signal "IN4")
		(26 "In12.Cu" signal "GND5")
		(28 "In13.Cu" signal "IN5")
		(30 "In14.Cu" signal "GND6")
		(32 "In15.Cu" signal "IN6")
		(34 "In16.Cu" signal "GND7")
		(2 "B.Cu" signal "BOTTOM")
		(9 "F.Adhes" user "F.Adhesive")
		(11 "B.Adhes" user "B.Adhesive")
		(13 "F.Paste" user "Package Geometry/Pastemask Top")
		(15 "B.Paste" user "Package Geometry/Pastemask Bottom")
		(5 "F.SilkS" user "Ref Des/Silkscreen Top")
		(7 "B.SilkS" user "Ref Des/Silkscreen Bottom")
		(1 "F.Mask" user "Board Geometry/Soldermask Top")
		(3 "B.Mask" user "Board Geometry/Soldermask Bottom")
		(17 "Dwgs.User" user "User.Drawings")
		(19 "Cmts.User" user "User.Comments")
		(21 "Eco1.User" user "User.Eco1")
		(23 "Eco2.User" user "User.Eco2")
		(25 "Edge.Cuts" user "Board Geometry/Outline")
		(27 "Margin" user)
		(31 "F.CrtYd" user "Package Geometry/Place Bound Top")
		(29 "B.CrtYd" user "Package Geometry/Place Bound Bottom")
		(35 "F.Fab" user "Ref Des/Assembly Top")
		(33 "B.Fab" user "Ref Des/Assembly Bottom")
	)
	(footprint ""
		(layer "F.Cu")
		(at 45.94606 -351.372932 90)
		(property "Reference" "PR278"
			(at 0 0 90)
			(layer "F.SilkS")
			(hide yes)
			(effects
				(font
					(size 1.27 1.27)
				)
			)
		)
		(property "Value" ""
			(at 0 0 90)
			(layer "F.Fab")
			(effects
				(font
					(size 1.27 1.27)
				)
			)
		)
		(duplicate_pad_numbers_are_jumpers no)
		(fp_line
			(start 0.7874 -0.4064)
			(end 0.7874 0.4064)
			(stroke
				(width 0.1524)
				(type default)
			)
			(layer "F.SilkS")
		)
		(fp_line
			(start -0.7874 -0.4064)
			(end 0.7874 -0.4064)
			(stroke
				(width 0.1524)
				(type default)
			)
			(layer "F.SilkS")
		)
		(fp_line
			(start 0.7874 0.4064)
			(end -0.7874 0.4064)
			(stroke
				(width 0.1524)
				(type default)
			)
			(layer "F.SilkS")
		)
		(fp_line
			(start -0.7874 0.4064)
			(end -0.7874 -0.4064)
			(stroke
				(width 0.1524)
				(type default)
			)
			(layer "F.SilkS")
		)
		(fp_line
			(start -0.12065 -0.305054)
			(end -0.12065 -0.2794)
			(stroke
				(width 0.1)
				(type default)
			)
			(layer "F.Fab")
		)
		(fp_line
			(start -0.67945 -0.305054)
			(end -0.12065 -0.305054)
			(stroke
				(width 0.1)
				(type default)
			)
			(layer "F.Fab")
		)
		(fp_line
			(start 0.67945 -0.3048)
			(end 0.67945 0.3048)
			(stroke
				(width 0.1)
				(type default)
			)
			(layer "F.Fab")
		)
		(fp_line
			(start 0.12065 -0.3048)
			(end 0.67945 -0.3048)
			(stroke
				(width 0.1)
				(type default)
			)
			(layer "F.Fab")
		)
		(fp_line
			(start 0.12065 -0.2794)
			(end 0.12065 -0.3048)
			(stroke
				(width 0.1)
				(type default)
			)
			(layer "F.Fab")
		)
		(fp_line
			(start -0.12065 -0.2794)
			(end 0.12065 -0.2794)
			(stroke
				(width 0.1)
				(type default)
			)
			(layer "F.Fab")
		)
		(fp_line
			(start 0.120396 0.2794)
			(end -0.12065 0.2794)
			(stroke
				(width 0.1)
				(type default)
			)
			(layer "F.Fab")
		)
		(fp_line
			(start -0.12065 0.2794)
			(end -0.12065 0.3048)
			(stroke
				(width 0.1)
				(type default)
			)
			(layer "F.Fab")
		)
		(fp_line
			(start 0.67945 0.3048)
			(end 0.120396 0.3048)
			(stroke
				(width 0.1)
				(type default)
			)
			(layer "F.Fab")
		)
		(fp_line
			(start 0.120396 0.3048)
			(end 0.120396 0.2794)
			(stroke
				(width 0.1)
				(type default)
			)
			(layer "F.Fab")
		)
		(fp_line
			(start -0.12065 0.3048)
			(end -0.67945 0.3048)
			(stroke
				(width 0.1)
				(type default)
			)
			(layer "F.Fab")
		)
		(fp_line
			(start -0.67945 0.3048)
			(end -0.67945 -0.305054)
			(stroke
				(width 0.1)
				(type default)
			)
			(layer "F.Fab")
		)
		(pad "1" smd circle
			(at -0.40005 0 90)
			(size 0 0)
			(layers "F.Cu" "F.Mask" "F.Paste")
			(net "SW_PVDDIO_P1_BOOT2")
		)
		(pad "2" smd circle
			(at 0.40005 0 90)
			(size 0 0)
			(layers "F.Cu" "F.Mask" "F.Paste")
			(net "SW_PVDDIO_P1_BOOT2_R")
		)
	)
	(footprint ""
		(layer "F.Cu")
		(at 165.509448 -51.81346 -90)
		(property "Reference" "C1920"
			(at 0 0 270)
			(layer "F.SilkS")
			(hide yes)
			(effects
				(font
					(size 1.27 1.27)
				)
			)
		)
		(property "Value" ""
			(at 0 0 270)
			(layer "F.Fab")
			(effects
				(font
					(size 1.27 1.27)
				)
			)
		)
		(duplicate_pad_numbers_are_jumpers no)
		(fp_line
			(start -1.2954 0.5842)
			(end -1.2954 -0.5842)
			(stroke
				(width 0.1524)
				(type default)
			)
			(layer "F.SilkS")
		)
		(fp_line
			(start 1.2954 0.5842)
			(end -1.2954 0.5842)
			(stroke
				(width 0.1524)
				(type default)
			)
			(layer "F.SilkS")
		)
		(fp_line
			(start -1.2954 -0.5842)
			(end 1.2954 -0.5842)
			(stroke
				(width 0.1524)
				(type default)
			)
			(layer "F.SilkS")
		)
		(fp_line
			(start 1.2954 -0.5842)
			(end 1.2954 0.5842)
			(stroke
				(width 0.1524)
				(type default)
			)
			(layer "F.SilkS")
		)
		(fp_line
			(start -0.8636 0.4572)
			(end -0.8636 0.4064)
			(stroke
				(width 0.1)
				(type default)
			)
			(layer "F.Fab")
		)
		(fp_line
			(start 0.8636 0.4572)
			(end -0.8636 0.4572)
			(stroke
				(width 0.1)
				(type default)
			)
			(layer "F.Fab")
		)
		(fp_line
			(start -1.1938 0.4064)
			(end -1.1938 -0.4064)
			(stroke
				(width 0.1)
				(type default)
			)
			(layer "F.Fab")
		)
		(fp_line
			(start -0.8636 0.4064)
			(end -1.1938 0.4064)
			(stroke
				(width 0.1)
				(type default)
			)
			(layer "F.Fab")
		)
		(fp_line
			(start 0.8636 0.4064)
			(end 0.8636 0.4572)
			(stroke
				(width 0.1)
				(type default)
			)
			(layer "F.Fab")
		)
		(fp_line
			(start 1.1938 0.4064)
			(end 0.8636 0.4064)
			(stroke
				(width 0.1)
				(type default)
			)
			(layer "F.Fab")
		)
		(fp_line
			(start -1.1938 -0.4064)
			(end -0.8636 -0.4064)
			(stroke
				(width 0.1)
				(type default)
			)
			(layer "F.Fab")
		)
		(fp_line
			(start -0.8636 -0.4064)
			(end -0.8636 -0.4572)
			(stroke
				(width 0.1)
				(type default)
			)
			(layer "F.Fab")
		)
		(fp_line
			(start 0.8636 -0.4064)
			(end 1.1938 -0.4064)
			(stroke
				(width 0.1)
				(type default)
			)
			(layer "F.Fab")
		)
		(fp_line
			(start 1.1938 -0.4064)
			(end 1.1938 0.4064)
			(stroke
				(width 0.1)
				(type default)
			)
			(layer "F.Fab")
		)
		(fp_line
			(start -0.8636 -0.4572)
			(end 0.8636 -0.4572)
			(stroke
				(width 0.1)
				(type default)
			)
			(layer "F.Fab")
		)
		(fp_line
			(start 0.8636 -0.4572)
			(end 0.8636 -0.4064)
			(stroke
				(width 0.1)
				(type default)
			)
			(layer "F.Fab")
		)
		(pad "1" smd rect
			(at -0.7366 0 180)
			(size 0.7112 0.8128)
			(layers "F.Cu" "F.Mask" "F.Paste")
			(net "P3V3_M2_0")
		)
		(pad "2" smd rect
			(at 0.7366 0 180)
			(size 0.7112 0.8128)
			(layers "F.Cu" "F.Mask" "F.Paste")
			(net "GND")
		)
	)
	(footprint ""
		(layer "F.Cu")
		(at 97.719642 -400.417792)
		(property "Reference" "R1215"
			(at 0 0 0)
			(layer "F.SilkS")
			(hide yes)
			(effects
				(font
					(size 1.27 1.27)
				)
			)
		)
		(property "Value" ""
			(at 0 0 0)
			(layer "F.Fab")
			(effects
				(font
					(size 1.27 1.27)
				)
			)
		)
		(duplicate_pad_numbers_are_jumpers no)
		(fp_line
			(start -0.32512 -0.175006)
			(end 0.32512 -0.175006)
			(stroke
				(width 0.1)
				(type default)
			)
			(layer "F.Fab")
		)
		(fp_line
			(start -0.32512 0.175006)
			(end -0.32512 -0.175006)
			(stroke
				(width 0.1)
				(type default)
			)
			(layer "F.Fab")
		)
		(fp_line
			(start 0.32512 -0.175006)
			(end 0.32512 0.175006)
			(stroke
				(width 0.1)
				(type default)
			)
			(layer "F.Fab")
		)
		(fp_line
			(start 0.32512 0.175006)
			(end -0.32512 0.175006)
			(stroke
				(width 0.1)
				(type default)
			)
			(layer "F.Fab")
		)
		(pad "1" smd rect
			(at -0.2667 0)
			(size 0.3048 0.381)
			(layers "F.Cu" "F.Mask" "F.Paste")
			(net "GND")
		)
		(pad "2" smd rect
			(at 0.2667 0 180)
			(size 0.3048 0.381)
			(layers "F.Cu" "F.Mask" "F.Paste")
			(net "RT_ROM_MUX1_OE_N")
		)
	)
)
